(kicad_pcb
	(version 20260206)
	(generator "pcbnew")
	(generator_version "10.0")
	(general
		(thickness 0.77098)
		(legacy_teardrops no)
	)
	(paper "A4")
	(title_block
		(title "gnss-m2-zed-f9t — M2_ZED-F9T_MODULE.PcbDoc")
		(comment 1 "Time Appliance Project (Time Card) / footprints 8-12 of 36")
	)
	(layers
		(0 "F.Cu" signal "L01-Top Layer")
		(4 "In1.Cu" signal "L02-Inner Layer")
		(6 "In2.Cu" signal "L03-Inner Layer")
		(2 "B.Cu" signal "L04-Bottom Layer")
		(9 "F.Adhes" user "F.Adhesive")
		(11 "B.Adhes" user "B.Adhesive")
		(13 "F.Paste" user "Top Paste")
		(15 "B.Paste" user "Bottom Paste")
		(5 "F.SilkS" user "Top Overlay")
		(7 "B.SilkS" user "Bottom Overlay")
		(1 "F.Mask" user "Top Solder")
		(3 "B.Mask" user "Bottom Solder")
		(17 "Dwgs.User" user "User.Drawings")
		(19 "Cmts.User" user "User.Comments")
		(21 "Eco1.User" user "User.Eco1")
		(23 "Eco2.User" user "User.Eco2")
		(25 "Edge.Cuts" user)
		(27 "Margin" user)
		(31 "F.CrtYd" user "Top Courtyard")
		(29 "B.CrtYd" user "Bottom Courtyard")
		(35 "F.Fab" user "Top Component Outline")
		(33 "B.Fab" user "Bottom Component Outline 2")
	)
	(footprint "Vault:RESC1005X40X25NL05T10"
		(layer "F.Cu")
		(at 148.901105 118.2036 90)
		(property "Reference" "R14"
			(at 1.599995 0.504296 90)
			(unlocked yes)
			(layer "F.SilkS")
			(effects
				(font
					(face "Arial")
					(size 0.48006 0.48006)
					(thickness 0.254)
				)
			)
		)
		(property "Value" "DNI_0_5%_0402"
			(at -2.385841 9.43298 0)
			(unlocked yes)
			(layer "F.SilkS")
			(hide yes)
			(effects
				(font
					(face "Arial")
					(size 0.96012 0.96012)
					(thickness 0.254)
				)
			)
		)
		(sheetname "03-M2_GoldFingers")
		(sheetfile "03-M2_GoldFingers.kicad_sch")
		(duplicate_pad_numbers_are_jumpers no)
		(fp_line
			(start 0.9 -0.45)
			(end 0.9 0.45)
			(stroke
				(width 0.05)
				(type solid)
			)
			(layer "F.CrtYd")
		)
		(fp_line
			(start -0.9 -0.45)
			(end 0.9 -0.45)
			(stroke
				(width 0.05)
				(type solid)
			)
			(layer "F.CrtYd")
		)
		(fp_line
			(start -0.9 -0.45)
			(end -0.9 0.45)
			(stroke
				(width 0.05)
				(type solid)
			)
			(layer "F.CrtYd")
		)
		(fp_line
			(start 0 -0.275)
			(end 0 0.275)
			(stroke
				(width 0.1)
				(type solid)
			)
			(layer "F.CrtYd")
		)
		(fp_line
			(start -0.275 0)
			(end 0.275 0)
			(stroke
				(width 0.1)
				(type solid)
			)
			(layer "F.CrtYd")
		)
		(fp_line
			(start -0.9 0.45)
			(end 0.9 0.45)
			(stroke
				(width 0.05)
				(type solid)
			)
			(layer "F.CrtYd")
		)
		(pad "1" smd rect
			(at -0.425 0 180)
			(size 0.55 0.6)
			(layers "F.Cu" "F.Mask" "F.Paste")
			(net "NetJ1_35")
		)
		(pad "2" smd rect
			(at 0.425 0 180)
			(size 0.55 0.6)
			(layers "F.Cu" "F.Mask" "F.Paste")
			(net "TP1")
		)
	)
	(footprint "Vault:FP-0402-L_1_0_0_05-W_0_5-IPC_B"
		(layer "F.Cu")
		(at 140.201105 85.0036 180)
		(property "Reference" "C9"
			(at 1.799995 0.180419 0)
			(unlocked yes)
			(layer "F.SilkS")
			(effects
				(font
					(face "Arial")
					(size 0.96012 0.96012)
					(thickness 0.254)
				)
			)
		)
		(property "Value" "100nF"
			(at 2.70399 2.099971 180)
			(unlocked yes)
			(layer "F.SilkS")
			(hide yes)
			(effects
				(font
					(face "Arial")
					(size 0.96012 0.96012)
					(thickness 0.254)
				)
			)
		)
		(sheetname "02-Antenna_Supervisor")
		(sheetfile "02-Antenna_Supervisor.kicad_sch")
		(duplicate_pad_numbers_are_jumpers no)
		(fp_line
			(start 0.73624 0.68624)
			(end -0.73624 0.68624)
			(stroke
				(width 0.2)
				(type solid)
			)
			(layer "F.SilkS")
		)
		(fp_line
			(start 0.73624 -0.68624)
			(end -0.73624 -0.68624)
			(stroke
				(width 0.2)
				(type solid)
			)
			(layer "F.SilkS")
		)
		(fp_line
			(start 0.88624 0.43624)
			(end -0.88624 0.43624)
			(stroke
				(width 0.2)
				(type solid)
			)
			(layer "F.CrtYd")
		)
		(fp_line
			(start 0.88624 -0.43624)
			(end 0.88624 0.43624)
			(stroke
				(width 0.2)
				(type solid)
			)
			(layer "F.CrtYd")
		)
		(fp_line
			(start 0.88624 -0.43624)
			(end -0.88624 -0.43624)
			(stroke
				(width 0.2)
				(type solid)
			)
			(layer "F.CrtYd")
		)
		(fp_line
			(start -0.88624 -0.43624)
			(end -0.88624 0.43624)
			(stroke
				(width 0.2)
				(type solid)
			)
			(layer "F.CrtYd")
		)
		(fp_line
			(start 0.88624 0.43624)
			(end -0.88624 0.43624)
			(stroke
				(width 0.2)
				(type solid)
			)
			(layer "F.Fab")
		)
		(fp_line
			(start 0.88624 -0.43624)
			(end 0.88624 0.43624)
			(stroke
				(width 0.2)
				(type solid)
			)
			(layer "F.Fab")
		)
		(fp_line
			(start 0.88624 -0.43624)
			(end -0.88624 -0.43624)
			(stroke
				(width 0.2)
				(type solid)
			)
			(layer "F.Fab")
		)
		(fp_line
			(start 0.5 0)
			(end -0.5 0)
			(stroke
				(width 0.1)
				(type solid)
			)
			(layer "F.Fab")
		)
		(fp_line
			(start 0 -0.5)
			(end 0 0.5)
			(stroke
				(width 0.1)
				(type solid)
			)
			(layer "F.Fab")
		)
		(fp_line
			(start -0.88624 -0.43624)
			(end -0.88624 0.43624)
			(stroke
				(width 0.2)
				(type solid)
			)
			(layer "F.Fab")
		)
		(fp_text user "${REFERENCE}"
			(at -0.00001 0.09601 180)
			(unlocked yes)
			(layer "F.Fab")
			(effects
				(font
					(face "Arial")
					(size 0.63 0.63)
					(thickness 0.1)
				)
				(justify left bottom)
			)
		)
		(pad "1" smd rect
			(at -0.42856 0 180)
			(size 0.61535 0.57247)
			(layers "F.Cu" "F.Mask" "F.Paste")
			(net "+3V3")
			(solder_mask_margin 0)
			(solder_paste_margin 0)
		)
		(pad "2" smd rect
			(at 0.42856 0 180)
			(size 0.61535 0.57247)
			(layers "F.Cu" "F.Mask" "F.Paste")
			(net "GND")
			(solder_mask_margin 0)
			(solder_paste_margin 0)
		)
	)
	(footprint "Vault:FP-LTST-C191KGKT-MFG"
		(layer "F.Cu")
		(at 155.901105 116.3036)
		(property "Reference" "D2"
			(at 2.300005 -0.490519 0)
			(unlocked yes)
			(layer "F.SilkS")
			(effects
				(font
					(face "Arial")
					(size 0.96012 0.96012)
					(thickness 0.254)
				)
			)
		)
		(property "Value" "LTST-C191KGKT"
			(at 7.705865 2.207911 0)
			(unlocked yes)
			(layer "F.SilkS")
			(hide yes)
			(effects
				(font
					(face "Arial")
					(size 0.96012 0.96012)
					(thickness 0.254)
				)
			)
		)
		(sheetname "01-M2_ZED-F9T_MODULE")
		(sheetfile "01-M2_ZED-F9T_MODULE.kicad_sch")
		(duplicate_pad_numbers_are_jumpers no)
		(fp_line
			(start -0.85 -0.775)
			(end 0.85 -0.775)
			(stroke
				(width 0.2)
				(type solid)
			)
			(layer "F.SilkS")
		)
		(fp_line
			(start -0.85 0.775)
			(end 0.85 0.775)
			(stroke
				(width 0.2)
				(type solid)
			)
			(layer "F.SilkS")
		)
		(fp_circle
			(center -0.99118 1.3)
			(end -0.99118 1.175)
			(stroke
				(width 0.25)
				(type solid)
			)
			(fill no)
			(layer "F.SilkS")
		)
		(fp_line
			(start -1.25 -0.55)
			(end 1.25 -0.55)
			(stroke
				(width 0.2)
				(type solid)
			)
			(layer "F.CrtYd")
		)
		(fp_line
			(start -1.25 0.55)
			(end -1.25 -0.55)
			(stroke
				(width 0.2)
				(type solid)
			)
			(layer "F.CrtYd")
		)
		(fp_line
			(start -1.25 0.55)
			(end 1.25 0.55)
			(stroke
				(width 0.2)
				(type solid)
			)
			(layer "F.CrtYd")
		)
		(fp_line
			(start 1.25 0.55)
			(end 1.25 -0.55)
			(stroke
				(width 0.2)
				(type solid)
			)
			(layer "F.CrtYd")
		)
		(fp_line
			(start -1.25 -0.55)
			(end 1.25 -0.55)
			(stroke
				(width 0.2)
				(type solid)
			)
			(layer "F.Fab")
		)
		(fp_line
			(start -1.25 0.55)
			(end -1.25 -0.55)
			(stroke
				(width 0.2)
				(type solid)
			)
			(layer "F.Fab")
		)
		(fp_line
			(start -1.25 0.55)
			(end 1.25 0.55)
			(stroke
				(width 0.2)
				(type solid)
			)
			(layer "F.Fab")
		)
		(fp_line
			(start -0.5 0)
			(end 0.5 0)
			(stroke
				(width 0.1)
				(type solid)
			)
			(layer "F.Fab")
		)
		(fp_line
			(start 0 0.5)
			(end 0 -0.5)
			(stroke
				(width 0.1)
				(type solid)
			)
			(layer "F.Fab")
		)
		(fp_line
			(start 1.25 0.55)
			(end 1.25 -0.55)
			(stroke
				(width 0.2)
				(type solid)
			)
			(layer "F.Fab")
		)
		(fp_text user "${REFERENCE}"
			(at 0 0.29534 0)
			(unlocked yes)
			(layer "F.Fab")
			(effects
				(font
					(face "Arial")
					(size 0.63 0.63)
					(thickness 0.1)
				)
				(justify left bottom)
			)
		)
		(pad "1" smd rect
			(at -0.75 0)
			(size 0.8 0.8)
			(layers "F.Cu" "F.Mask" "F.Paste")
			(net "NetD2_1")
			(solder_mask_margin 0)
			(solder_paste_margin 0)
		)
		(pad "2" smd rect
			(at 0.75 0)
			(size 0.8 0.8)
			(layers "F.Cu" "F.Mask" "F.Paste")
			(net "TP2")
			(solder_mask_margin 0)
			(solder_paste_margin 0)
		)
	)
	(footprint "Vault:FP-PESD0402-MFG"
		(layer "F.Cu")
		(at 155.255595 88.43974 180)
		(property "Reference" "D1"
			(at -2.34551 0.126659 0)
			(unlocked yes)
			(layer "F.SilkS")
			(effects
				(font
					(face "Arial")
					(size 0.96012 0.96012)
					(thickness 0.254)
				)
			)
		)
		(property "Value" "PESD0402-140"
			(at 7.75688 2.131721 180)
			(unlocked yes)
			(layer "F.SilkS")
			(hide yes)
			(effects
				(font
					(face "Arial")
					(size 0.96012 0.96012)
					(thickness 0.254)
				)
			)
		)
		(sheetname "02-Antenna_Supervisor")
		(sheetfile "02-Antenna_Supervisor.kicad_sch")
		(duplicate_pad_numbers_are_jumpers no)
		(fp_line
			(start 1.15 0.425)
			(end -1.15 0.425)
			(stroke
				(width 0.2)
				(type solid)
			)
			(layer "F.CrtYd")
		)
		(fp_line
			(start 1.15 -0.425)
			(end 1.15 0.425)
			(stroke
				(width 0.2)
				(type solid)
			)
			(layer "F.CrtYd")
		)
		(fp_line
			(start 1.15 -0.425)
			(end -1.15 -0.425)
			(stroke
				(width 0.2)
				(type solid)
			)
			(layer "F.CrtYd")
		)
		(fp_line
			(start -1.15 -0.425)
			(end -1.15 0.425)
			(stroke
				(width 0.2)
				(type solid)
			)
			(layer "F.CrtYd")
		)
		(fp_line
			(start 1.15 0.425)
			(end -1.15 0.425)
			(stroke
				(width 0.2)
				(type solid)
			)
			(layer "F.Fab")
		)
		(fp_line
			(start 1.15 -0.425)
			(end 1.15 0.425)
			(stroke
				(width 0.2)
				(type solid)
			)
			(layer "F.Fab")
		)
		(fp_line
			(start 1.15 -0.425)
			(end -1.15 -0.425)
			(stroke
				(width 0.2)
				(type solid)
			)
			(layer "F.Fab")
		)
		(fp_line
			(start 0.5 0)
			(end -0.49999 0)
			(stroke
				(width 0.1)
				(type solid)
			)
			(layer "F.Fab")
		)
		(fp_line
			(start 0 -0.49999)
			(end 0 0.5)
			(stroke
				(width 0.1)
				(type solid)
			)
			(layer "F.Fab")
		)
		(fp_line
			(start -1.15 -0.425)
			(end -1.15 0.425)
			(stroke
				(width 0.2)
				(type solid)
			)
			(layer "F.Fab")
		)
		(fp_text user "${REFERENCE}"
			(at -0.00001 0.10712 180)
			(unlocked yes)
			(layer "F.Fab")
			(effects
				(font
					(face "Arial")
					(size 0.63 0.63)
					(thickness 0.1)
				)
				(justify left bottom)
			)
		)
		(pad "1" smd rect
			(at -0.625 0 180)
			(size 0.85 0.65)
			(layers "F.Cu" "F.Mask" "F.Paste")
			(net "GND")
			(solder_mask_margin 0)
			(solder_paste_margin 0)
		)
		(pad "2" smd rect
			(at 0.625 0 180)
			(size 0.85 0.65)
			(layers "F.Cu" "F.Mask" "F.Paste")
			(net "RF_ANT")
			(solder_mask_margin 0)
			(solder_paste_margin 0)
		)
	)
	(footprint "Vault:RESC1005X40X25NL05T10"
		(layer "F.Cu")
		(at 145.401105 114.8036 180)
		(property "Reference" "R2"
			(at 2.099995 0.095704 0)
			(unlocked yes)
			(layer "F.SilkS")
			(effects
				(font
					(face "Arial")
					(size 0.48006 0.48006)
					(thickness 0.254)
				)
			)
		)
		(property "Value" "0_5%_0402"
			(at 7.604675 1.877841 180)
			(unlocked yes)
			(layer "F.SilkS")
			(hide yes)
			(effects
				(font
					(face "Arial")
					(size 0.96012 0.96012)
					(thickness 0.254)
				)
			)
		)
		(sheetname "01-M2_ZED-F9T_MODULE")
		(sheetfile "01-M2_ZED-F9T_MODULE.kicad_sch")
		(duplicate_pad_numbers_are_jumpers no)
		(fp_line
			(start 0.9 0.45)
			(end -0.9 0.45)
			(stroke
				(width 0.05)
				(type solid)
			)
			(layer "F.CrtYd")
		)
		(fp_line
			(start 0.9 -0.45)
			(end 0.9 0.45)
			(stroke
				(width 0.05)
				(type solid)
			)
			(layer "F.CrtYd")
		)
		(fp_line
			(start 0.9 -0.45)
			(end -0.9 -0.45)
			(stroke
				(width 0.05)
				(type solid)
			)
			(layer "F.CrtYd")
		)
		(fp_line
			(start 0.275 0)
			(end -0.275 0)
			(stroke
				(width 0.1)
				(type solid)
			)
			(layer "F.CrtYd")
		)
		(fp_line
			(start 0 -0.275)
			(end 0 0.275)
			(stroke
				(width 0.1)
				(type solid)
			)
			(layer "F.CrtYd")
		)
		(fp_line
			(start -0.9 -0.45)
			(end -0.9 0.45)
			(stroke
				(width 0.05)
				(type solid)
			)
			(layer "F.CrtYd")
		)
		(pad "1" smd rect
			(at -0.425 0 270)
			(size 0.55 0.6)
			(layers "F.Cu" "F.Mask" "F.Paste")
			(net "TX_GPS_CONN")
		)
		(pad "2" smd rect
			(at 0.425 0 270)
			(size 0.55 0.6)
			(layers "F.Cu" "F.Mask" "F.Paste")
			(net "NetR2_2")
		)
	)
)
